# T6G (Grand Teton) — schematic netlist excerpt (pin names and nets, part order shuffled) for the footprints in the layout excerpt that follows; sources: Cadence DE-HDL packaged netlist, KiCad conversion of 04192023_DAF0TMB3IC0_F0TG_MB_C_brd_V02_OCP.brd

C40  Q_CAP  0.01UF 50V 10% EMPTY  pkg C0402  page 140 : A = P12V_OCP_V3_2 ; B = P12V_OCP_GATE_2
R6175  Q_RES  1K 1% EMPTY  pkg 0402LF  page 112 : A = P3V3_AUX ; B = FM_P2E_BUF2_RXDET

(kicad_pcb
	(version 20260206)
	(generator "pcbnew")
	(generator_version "10.0")
	(general
		(thickness 1.6)
		(legacy_teardrops no)
	)
	(paper "A4")
	(title_block
		(title "04192023_DAF0TMB3IC0_F0TG_MB_C_brd_V02_OCP.brd")
		(comment 1 "Grand Teton / footprints 2212-2213 of 8354")
	)
	(layers
		(0 "F.Cu" signal "TOP")
		(4 "In1.Cu" signal "GND")
		(6 "In2.Cu" signal "IN1")
		(8 "In3.Cu" signal "GND1")
		(10 "In4.Cu" signal "IN2")
		(12 "In5.Cu" signal "GND2")
		(14 "In6.Cu" signal "IN3")
		(16 "In7.Cu" signal "GND3")
		(18 "In8.Cu" signal "VCC")
		(20 "In9.Cu" signal "VCC1")
		(22 "In10.Cu" signal "GND4")
		(24 "In11.Cu" signal "IN4")
		(26 "In12.Cu" signal "GND5")
		(28 "In13.Cu" signal "IN5")
		(30 "In14.Cu" signal "GND6")
		(32 "In15.Cu" signal "IN6")
		(34 "In16.Cu" signal "GND7")
		(2 "B.Cu" signal "BOTTOM")
		(9 "F.Adhes" user "F.Adhesive")
		(11 "B.Adhes" user "B.Adhesive")
		(13 "F.Paste" user "Package Geometry/Pastemask Top")
		(15 "B.Paste" user "Package Geometry/Pastemask Bottom")
		(5 "F.SilkS" user "Ref Des/Silkscreen Top")
		(7 "B.SilkS" user "Ref Des/Silkscreen Bottom")
		(1 "F.Mask" user "Board Geometry/Soldermask Top")
		(3 "B.Mask" user "Board Geometry/Soldermask Bottom")
		(17 "Dwgs.User" user "User.Drawings")
		(19 "Cmts.User" user "User.Comments")
		(21 "Eco1.User" user "User.Eco1")
		(23 "Eco2.User" user "User.Eco2")
		(25 "Edge.Cuts" user "Board Geometry/Outline")
		(27 "Margin" user)
		(31 "F.CrtYd" user "Package Geometry/Place Bound Top")
		(29 "B.CrtYd" user "Package Geometry/Place Bound Bottom")
		(35 "F.Fab" user "Ref Des/Assembly Top")
		(33 "B.Fab" user "Ref Des/Assembly Bottom")
	)
	(footprint ""
		(layer "F.Cu")
		(at 19.666458 -418.690298 90)
		(property "Reference" "R6175"
			(at 0 0 90)
			(layer "F.SilkS")
			(hide yes)
			(effects
				(font
					(size 1.27 1.27)
				)
			)
		)
		(property "Value" ""
			(at 0 0 90)
			(layer "F.Fab")
			(effects
				(font
					(size 1.27 1.27)
				)
			)
		)
		(duplicate_pad_numbers_are_jumpers no)
		(fp_line
			(start 0.7874 -0.4064)
			(end 0.7874 0.4064)
			(stroke
				(width 0.1524)
				(type default)
			)
			(layer "F.SilkS")
		)
		(fp_line
			(start -0.7874 -0.4064)
			(end 0.7874 -0.4064)
			(stroke
				(width 0.1524)
				(type default)
			)
			(layer "F.SilkS")
		)
		(fp_line
			(start 0.7874 0.4064)
			(end -0.7874 0.4064)
			(stroke
				(width 0.1524)
				(type default)
			)
			(layer "F.SilkS")
		)
		(fp_line
			(start -0.7874 0.4064)
			(end -0.7874 -0.4064)
			(stroke
				(width 0.1524)
				(type default)
			)
			(layer "F.SilkS")
		)
		(fp_line
			(start -0.12065 -0.305054)
			(end -0.12065 -0.2794)
			(stroke
				(width 0.1)
				(type default)
			)
			(layer "F.Fab")
		)
		(fp_line
			(start -0.67945 -0.305054)
			(end -0.12065 -0.305054)
			(stroke
				(width 0.1)
				(type default)
			)
			(layer "F.Fab")
		)
		(fp_line
			(start 0.67945 -0.3048)
			(end 0.67945 0.3048)
			(stroke
				(width 0.1)
				(type default)
			)
			(layer "F.Fab")
		)
		(fp_line
			(start 0.12065 -0.3048)
			(end 0.67945 -0.3048)
			(stroke
				(width 0.1)
				(type default)
			)
			(layer "F.Fab")
		)
		(fp_line
			(start 0.12065 -0.2794)
			(end 0.12065 -0.3048)
			(stroke
				(width 0.1)
				(type default)
			)
			(layer "F.Fab")
		)
		(fp_line
			(start -0.12065 -0.2794)
			(end 0.12065 -0.2794)
			(stroke
				(width 0.1)
				(type default)
			)
			(layer "F.Fab")
		)
		(fp_line
			(start 0.120396 0.2794)
			(end -0.12065 0.2794)
			(stroke
				(width 0.1)
				(type default)
			)
			(layer "F.Fab")
		)
		(fp_line
			(start -0.12065 0.2794)
			(end -0.12065 0.3048)
			(stroke
				(width 0.1)
				(type default)
			)
			(layer "F.Fab")
		)
		(fp_line
			(start 0.67945 0.3048)
			(end 0.120396 0.3048)
			(stroke
				(width 0.1)
				(type default)
			)
			(layer "F.Fab")
		)
		(fp_line
			(start 0.120396 0.3048)
			(end 0.120396 0.2794)
			(stroke
				(width 0.1)
				(type default)
			)
			(layer "F.Fab")
		)
		(fp_line
			(start -0.12065 0.3048)
			(end -0.67945 0.3048)
			(stroke
				(width 0.1)
				(type default)
			)
			(layer "F.Fab")
		)
		(fp_line
			(start -0.67945 0.3048)
			(end -0.67945 -0.305054)
			(stroke
				(width 0.1)
				(type default)
			)
			(layer "F.Fab")
		)
		(pad "1" smd circle
			(at -0.40005 0 90)
			(size 0 0)
			(layers "F.Cu" "F.Mask" "F.Paste")
			(net "P3V3_AUX")
		)
		(pad "2" smd circle
			(at 0.40005 0 90)
			(size 0 0)
			(layers "F.Cu" "F.Mask" "F.Paste")
			(net "FM_P2E_BUF2_RXDET")
		)
	)
	(footprint ""
		(layer "F.Cu")
		(at 80.924146 -24.346408 180)
		(property "Reference" "C40"
			(at 0 0 180)
			(layer "F.SilkS")
			(hide yes)
			(effects
				(font
					(size 1.27 1.27)
				)
			)
		)
		(property "Value" ""
			(at 0 0 180)
			(layer "F.Fab")
			(effects
				(font
					(size 1.27 1.27)
				)
			)
		)
		(duplicate_pad_numbers_are_jumpers no)
		(fp_line
			(start 0.7874 0.4064)
			(end -0.7874 0.4064)
			(stroke
				(width 0.1524)
				(type default)
			)
			(layer "F.SilkS")
		)
		(fp_line
			(start 0.7874 -0.4064)
			(end 0.7874 0.4064)
			(stroke
				(width 0.1524)
				(type default)
			)
			(layer "F.SilkS")
		)
		(fp_line
			(start -0.7874 0.4064)
			(end -0.7874 -0.4064)
			(stroke
				(width 0.1524)
				(type default)
			)
			(layer "F.SilkS")
		)
		(fp_line
			(start -0.7874 -0.4064)
			(end 0.7874 -0.4064)
			(stroke
				(width 0.1524)
				(type default)
			)
			(layer "F.SilkS")
		)
		(fp_line
			(start 0.67945 0.3048)
			(end 0.120396 0.3048)
			(stroke
				(width 0.1)
				(type default)
			)
			(layer "F.Fab")
		)
		(fp_line
			(start 0.67945 -0.3048)
			(end 0.67945 0.3048)
			(stroke
				(width 0.1)
				(type default)
			)
			(layer "F.Fab")
		)
		(fp_line
			(start 0.12065 -0.2794)
			(end 0.12065 -0.3048)
			(stroke
				(width 0.1)
				(type default)
			)
			(layer "F.Fab")
		)
		(fp_line
			(start 0.12065 -0.3048)
			(end 0.67945 -0.3048)
			(stroke
				(width 0.1)
				(type default)
			)
			(layer "F.Fab")
		)
		(fp_line
			(start 0.120396 0.3048)
			(end 0.120396 0.2794)
			(stroke
				(width 0.1)
				(type default)
			)
			(layer "F.Fab")
		)
		(fp_line
			(start 0.120396 0.2794)
			(end -0.12065 0.2794)
			(stroke
				(width 0.1)
				(type default)
			)
			(layer "F.Fab")
		)
		(fp_line
			(start -0.12065 0.3048)
			(end -0.67945 0.3048)
			(stroke
				(width 0.1)
				(type default)
			)
			(layer "F.Fab")
		)
		(fp_line
			(start -0.12065 0.2794)
			(end -0.12065 0.3048)
			(stroke
				(width 0.1)
				(type default)
			)
			(layer "F.Fab")
		)
		(fp_line
			(start -0.12065 -0.2794)
			(end 0.12065 -0.2794)
			(stroke
				(width 0.1)
				(type default)
			)
			(layer "F.Fab")
		)
		(fp_line
			(start -0.12065 -0.305054)
			(end -0.12065 -0.2794)
			(stroke
				(width 0.1)
				(type default)
			)
			(layer "F.Fab")
		)
		(fp_line
			(start -0.67945 0.3048)
			(end -0.67945 -0.305054)
			(stroke
				(width 0.1)
				(type default)
			)
			(layer "F.Fab")
		)
		(fp_line
			(start -0.67945 -0.305054)
			(end -0.12065 -0.305054)
			(stroke
				(width 0.1)
				(type default)
			)
			(layer "F.Fab")
		)
		(pad "1" smd circle
			(at -0.40005 0 180)
			(size 0 0)
			(layers "F.Cu" "F.Mask" "F.Paste")
			(net "P12V_OCP_V3_2")
		)
		(pad "2" smd circle
			(at 0.40005 0 180)
			(size 0 0)
			(layers "F.Cu" "F.Mask" "F.Paste")
			(net "P12V_OCP_GATE_2")
		)
	)
)
